(kicad_pcb
	(version 20260206)
	(generator "pcbnew")
	(generator_version "10.0")
	(general
		(thickness 1.6)
		(legacy_teardrops no)
	)
	(paper "A4")
	(title_block
		(title "panther-plus-userver — 13130-1b_20150205.brd")
		(comment 1 "Honey Badger (Wiwynn) / footprints 1079-1086 of 1509")
	)
	(layers
		(0 "F.Cu" signal "TOP")
		(4 "In1.Cu" signal "L2")
		(6 "In2.Cu" signal "L3")
		(8 "In3.Cu" signal "L4")
		(10 "In4.Cu" signal "L5")
		(12 "In5.Cu" signal "L6")
		(14 "In6.Cu" signal "L7")
		(16 "In7.Cu" signal "L8")
		(18 "In8.Cu" signal "L9")
		(20 "In9.Cu" signal "L10")
		(22 "In10.Cu" signal "L11")
		(2 "B.Cu" signal "BOTTOM")
		(9 "F.Adhes" user "F.Adhesive")
		(11 "B.Adhes" user "B.Adhesive")
		(13 "F.Paste" user "Package Geometry/Pastemask Top")
		(15 "B.Paste" user "Package Geometry/Pastemask Bottom")
		(5 "F.SilkS" user "Ref Des/Silkscreen Top")
		(7 "B.SilkS" user "Ref Des/Silkscreen Bottom")
		(1 "F.Mask" user "Board Geometry/Soldermask Top")
		(3 "B.Mask" user "Board Geometry/Soldermask Bottom")
		(17 "Dwgs.User" user "User.Drawings")
		(19 "Cmts.User" user "User.Comments")
		(21 "Eco1.User" user "User.Eco1")
		(23 "Eco2.User" user "User.Eco2")
		(25 "Edge.Cuts" user "Board Geometry/Outline")
		(27 "Margin" user)
		(31 "F.CrtYd" user "Package Geometry/Place Bound Top")
		(29 "B.CrtYd" user "Package Geometry/Place Bound Bottom")
		(35 "F.Fab" user "Ref Des/Assembly Top")
		(33 "B.Fab" user "Ref Des/Assembly Bottom")
	)
	(footprint ""
		(layer "B.Cu")
		(at 38.735 -43.561 -90)
		(property "Reference" "R125"
			(at 0 0 90)
			(layer "B.SilkS")
			(hide yes)
			(effects
				(font
					(size 1.27 1.27)
				)
				(justify mirror)
			)
		)
		(property "Value" "0R2J-2-GP"
			(at -1.7907 -1.1176 270)
			(unlocked yes)
			(layer "B.Fab")
			(hide yes)
			(effects
				(font
					(size 1.016 1.016)
					(thickness 0.1524)
				)
				(justify mirror)
			)
		)
		(property "Device Type" "R402H16"
			(at -1.7907 -2.6416 270)
			(unlocked yes)
			(layer "B.Fab")
			(hide yes)
			(effects
				(font
					(size 1.016 1.016)
					(thickness 0.1524)
				)
				(justify mirror)
			)
		)
		(duplicate_pad_numbers_are_jumpers no)
		(fp_rect
			(start 0.381 0.8382)
			(end -0.381 -0.8382)
			(stroke
				(width 0)
				(type default)
			)
			(fill no)
			(layer "B.CrtYd")
		)
		(fp_rect
			(start 0.381 0.8382)
			(end -0.381 -0.8382)
			(stroke
				(width 0)
				(type default)
			)
			(fill no)
			(layer "B.Fab")
		)
		(pad "1" smd custom
			(at 0 -0.4318 90)
			(size 0.127 0.127)
			(layers "B.Cu" "B.Mask" "B.Paste")
			(net "XTAL_CLK_GEN_OUT_R")
			(options
				(clearance outline)
				(anchor circle)
			)
			(primitives
				(gr_poly
					(pts
						(arc
							(start -0.2032 0.2794)
							(mid -0.239121 0.264521)
							(end -0.254 0.2286)
						)
						(arc
							(start -0.254 -0.2286)
							(mid -0.239121 -0.264521)
							(end -0.2032 -0.2794)
						)
						(arc
							(start 0.2032 -0.2794)
							(mid 0.239121 -0.264521)
							(end 0.254 -0.2286)
						)
						(arc
							(start 0.254 0.2286)
							(mid 0.239121 0.264521)
							(end 0.2032 0.2794)
						)
					)
					(width 0)
					(fill yes)
				)
			)
		)
		(pad "2" smd custom
			(at 0 0.4318 90)
			(size 0.127 0.127)
			(layers "B.Cu" "B.Mask" "B.Paste")
			(net "XTAL_CLK_GEN_OUT")
			(options
				(clearance outline)
				(anchor circle)
			)
			(primitives
				(gr_poly
					(pts
						(arc
							(start -0.2032 0.2794)
							(mid -0.239121 0.264521)
							(end -0.254 0.2286)
						)
						(arc
							(start -0.254 -0.2286)
							(mid -0.239121 -0.264521)
							(end -0.2032 -0.2794)
						)
						(arc
							(start 0.2032 -0.2794)
							(mid 0.239121 -0.264521)
							(end 0.254 -0.2286)
						)
						(arc
							(start 0.254 0.2286)
							(mid 0.239121 0.264521)
							(end 0.2032 0.2794)
						)
					)
					(width 0)
					(fill yes)
				)
			)
		)
	)
	(footprint ""
		(layer "B.Cu")
		(at 84.836 -14.478)
		(property "Reference" "PC203"
			(at 0 0 0)
			(layer "B.SilkS")
			(hide yes)
			(effects
				(font
					(size 1.27 1.27)
				)
				(justify mirror)
			)
		)
		(property "Value" "SCD1U10V2KX-5GP"
			(at -1.1811 -2.7051 0)
			(unlocked yes)
			(layer "B.Fab")
			(hide yes)
			(effects
				(font
					(size 1.016 1.016)
					(thickness 0.1524)
				)
				(justify mirror)
			)
		)
		(property "Device Type" "C402H22"
			(at -1.1811 -4.2291 0)
			(unlocked yes)
			(layer "B.Fab")
			(hide yes)
			(effects
				(font
					(size 1.016 1.016)
					(thickness 0.1524)
				)
				(justify mirror)
			)
		)
		(duplicate_pad_numbers_are_jumpers no)
		(fp_rect
			(start 0.381 0.7366)
			(end -0.381 -0.7366)
			(stroke
				(width 0)
				(type default)
			)
			(fill no)
			(layer "B.CrtYd")
		)
		(fp_rect
			(start 0.381 0.7366)
			(end -0.381 -0.7366)
			(stroke
				(width 0)
				(type default)
			)
			(fill no)
			(layer "B.Fab")
		)
		(pad "1" smd custom
			(at 0 -0.4572 180)
			(size 0.1143 0.1143)
			(layers "B.Cu" "B.Mask" "B.Paste")
			(net "TPS74801_1V35_OUT")
			(options
				(clearance outline)
				(anchor circle)
			)
			(primitives
				(gr_poly
					(pts
						(arc
							(start -0.254 0.1778)
							(mid -0.239121 0.213721)
							(end -0.2032 0.2286)
						)
						(arc
							(start 0.2032 0.2286)
							(mid 0.239121 0.213721)
							(end 0.254 0.1778)
						)
						(arc
							(start 0.254 -0.1778)
							(mid 0.239121 -0.213721)
							(end 0.2032 -0.2286)
						)
						(arc
							(start -0.2032 -0.2286)
							(mid -0.239121 -0.213721)
							(end -0.254 -0.1778)
						)
					)
					(width 0)
					(fill yes)
				)
			)
		)
		(pad "2" smd custom
			(at 0 0.4572 180)
			(size 0.1143 0.1143)
			(layers "B.Cu" "B.Mask" "B.Paste")
			(net "GND")
			(options
				(clearance outline)
				(anchor circle)
			)
			(primitives
				(gr_poly
					(pts
						(arc
							(start -0.254 0.1778)
							(mid -0.239121 0.213721)
							(end -0.2032 0.2286)
						)
						(arc
							(start 0.2032 0.2286)
							(mid 0.239121 0.213721)
							(end 0.254 0.1778)
						)
						(arc
							(start 0.254 -0.1778)
							(mid 0.239121 -0.213721)
							(end 0.2032 -0.2286)
						)
						(arc
							(start -0.2032 -0.2286)
							(mid -0.239121 -0.213721)
							(end -0.254 -0.1778)
						)
					)
					(width 0)
					(fill yes)
				)
			)
		)
	)
	(footprint ""
		(layer "B.Cu")
		(at 74.93 -49.911 90)
		(property "Reference" "R310"
			(at 0 0 90)
			(layer "B.SilkS")
			(hide yes)
			(effects
				(font
					(size 1.27 1.27)
				)
				(justify mirror)
			)
		)
		(property "Value" "4K7R2F-GP"
			(at -0.064008 -3.993896 90)
			(unlocked yes)
			(layer "B.Fab")
			(hide yes)
			(effects
				(font
					(size 1.016 1.016)
					(thickness 0.1524)
				)
				(justify mirror)
			)
		)
		(property "Device Type" "R402H16"
			(at -0.064008 -5.517896 90)
			(unlocked yes)
			(layer "B.Fab")
			(hide yes)
			(effects
				(font
					(size 1.016 1.016)
					(thickness 0.1524)
				)
				(justify mirror)
			)
		)
		(duplicate_pad_numbers_are_jumpers no)
		(fp_rect
			(start 0.381 0.8382)
			(end -0.381 -0.8382)
			(stroke
				(width 0)
				(type default)
			)
			(fill no)
			(layer "B.CrtYd")
		)
		(fp_rect
			(start 0.381 0.8382)
			(end -0.381 -0.8382)
			(stroke
				(width 0)
				(type default)
			)
			(fill no)
			(layer "B.Fab")
		)
		(pad "1" smd custom
			(at 0 -0.4318 270)
			(size 0.127 0.127)
			(layers "B.Cu" "B.Mask" "B.Paste")
			(net "P3V3")
			(options
				(clearance outline)
				(anchor circle)
			)
			(primitives
				(gr_poly
					(pts
						(arc
							(start -0.2032 0.2794)
							(mid -0.239121 0.264521)
							(end -0.254 0.2286)
						)
						(arc
							(start -0.254 -0.2286)
							(mid -0.239121 -0.264521)
							(end -0.2032 -0.2794)
						)
						(arc
							(start 0.2032 -0.2794)
							(mid 0.239121 -0.264521)
							(end 0.254 -0.2286)
						)
						(arc
							(start 0.254 0.2286)
							(mid 0.239121 0.264521)
							(end 0.2032 0.2794)
						)
					)
					(width 0)
					(fill yes)
				)
			)
		)
		(pad "2" smd custom
			(at 0 0.4318 270)
			(size 0.127 0.127)
			(layers "B.Cu" "B.Mask" "B.Paste")
			(net "BIOS_POST_CMPLT#")
			(options
				(clearance outline)
				(anchor circle)
			)
			(primitives
				(gr_poly
					(pts
						(arc
							(start -0.2032 0.2794)
							(mid -0.239121 0.264521)
							(end -0.254 0.2286)
						)
						(arc
							(start -0.254 -0.2286)
							(mid -0.239121 -0.264521)
							(end -0.2032 -0.2794)
						)
						(arc
							(start 0.2032 -0.2794)
							(mid 0.239121 -0.264521)
							(end 0.254 -0.2286)
						)
						(arc
							(start 0.254 0.2286)
							(mid 0.239121 0.264521)
							(end 0.2032 0.2794)
						)
					)
					(width 0)
					(fill yes)
				)
			)
		)
	)
	(footprint ""
		(layer "B.Cu")
		(at 71.952866 -26.243534)
		(property "Reference" "TP45"
			(at 0 0 0)
			(layer "B.SilkS")
			(hide yes)
			(effects
				(font
					(size 1.27 1.27)
				)
				(justify mirror)
			)
		)
		(property "Value" "TPAD24"
			(at 0 -2.9972 0)
			(unlocked yes)
			(layer "B.Fab")
			(hide yes)
			(effects
				(font
					(size 1.016 1.016)
					(thickness 0.1524)
				)
				(justify mirror)
			)
		)
		(property "Device Type" "TPAD24"
			(at 0 -4.5212 0)
			(unlocked yes)
			(layer "B.Fab")
			(hide yes)
			(effects
				(font
					(size 1.016 1.016)
					(thickness 0.1524)
				)
				(justify mirror)
			)
		)
		(duplicate_pad_numbers_are_jumpers no)
		(fp_poly
			(pts
				(arc
					(start 0.3048 0)
					(mid -0.3048 0)
					(end 0.3048 0)
				)
			)
			(stroke
				(width 0)
				(type default)
			)
			(fill no)
			(layer "B.CrtYd")
		)
		(fp_poly
			(pts
				(arc
					(start 0.6096 0)
					(mid -0.6096 0)
					(end 0.6096 0)
				)
			)
			(stroke
				(width 0)
				(type default)
			)
			(fill no)
			(layer "B.Fab")
		)
		(pad "1" smd circle
			(at 0 0 180)
			(size 0.6096 0.6096)
			(layers "B.Cu" "B.Mask" "B.Paste")
			(net "GBE_SDP0")
		)
	)
	(footprint ""
		(layer "B.Cu")
		(at 138.303 -23.622 90)
		(property "Reference" "C162"
			(at 0 0 90)
			(layer "B.SilkS")
			(hide yes)
			(effects
				(font
					(size 1.27 1.27)
				)
				(justify mirror)
			)
		)
		(property "Value" "SCD1U10V2KX-5GP"
			(at -1.1811 -2.7051 90)
			(unlocked yes)
			(layer "B.Fab")
			(hide yes)
			(effects
				(font
					(size 1.016 1.016)
					(thickness 0.1524)
				)
				(justify mirror)
			)
		)
		(property "Device Type" "C402H22"
			(at -1.1811 -4.2291 90)
			(unlocked yes)
			(layer "B.Fab")
			(hide yes)
			(effects
				(font
					(size 1.016 1.016)
					(thickness 0.1524)
				)
				(justify mirror)
			)
		)
		(duplicate_pad_numbers_are_jumpers no)
		(fp_rect
			(start 0.381 0.7366)
			(end -0.381 -0.7366)
			(stroke
				(width 0)
				(type default)
			)
			(fill no)
			(layer "B.CrtYd")
		)
		(fp_rect
			(start 0.381 0.7366)
			(end -0.381 -0.7366)
			(stroke
				(width 0)
				(type default)
			)
			(fill no)
			(layer "B.Fab")
		)
		(pad "1" smd custom
			(at 0 -0.4572 270)
			(size 0.1143 0.1143)
			(layers "B.Cu" "B.Mask" "B.Paste")
			(net "P3V3_STBY")
			(options
				(clearance outline)
				(anchor circle)
			)
			(primitives
				(gr_poly
					(pts
						(arc
							(start -0.254 0.1778)
							(mid -0.239121 0.213721)
							(end -0.2032 0.2286)
						)
						(arc
							(start 0.2032 0.2286)
							(mid 0.239121 0.213721)
							(end 0.254 0.1778)
						)
						(arc
							(start 0.254 -0.1778)
							(mid 0.239121 -0.213721)
							(end 0.2032 -0.2286)
						)
						(arc
							(start -0.2032 -0.2286)
							(mid -0.239121 -0.213721)
							(end -0.254 -0.1778)
						)
					)
					(width 0)
					(fill yes)
				)
			)
		)
		(pad "2" smd custom
			(at 0 0.4572 270)
			(size 0.1143 0.1143)
			(layers "B.Cu" "B.Mask" "B.Paste")
			(net "GND")
			(options
				(clearance outline)
				(anchor circle)
			)
			(primitives
				(gr_poly
					(pts
						(arc
							(start -0.254 0.1778)
							(mid -0.239121 0.213721)
							(end -0.2032 0.2286)
						)
						(arc
							(start 0.2032 0.2286)
							(mid 0.239121 0.213721)
							(end 0.254 0.1778)
						)
						(arc
							(start 0.254 -0.1778)
							(mid 0.239121 -0.213721)
							(end 0.2032 -0.2286)
						)
						(arc
							(start -0.2032 -0.2286)
							(mid -0.239121 -0.213721)
							(end -0.254 -0.1778)
						)
					)
					(width 0)
					(fill yes)
				)
			)
		)
	)
	(footprint ""
		(layer "B.Cu")
		(at 16.002 -51.181 180)
		(property "Reference" "R501"
			(at 0 0 0)
			(layer "B.SilkS")
			(hide yes)
			(effects
				(font
					(size 1.27 1.27)
				)
				(justify mirror)
			)
		)
		(property "Value" "150R3F-GP"
			(at 0.0254 -2.0193 180)
			(unlocked yes)
			(layer "B.Fab")
			(hide yes)
			(effects
				(font
					(size 1.016 1.016)
					(thickness 0.1524)
				)
				(justify mirror)
			)
		)
		(property "Device Type" "R603H22"
			(at 0.0254 -3.5433 180)
			(unlocked yes)
			(layer "B.Fab")
			(hide yes)
			(effects
				(font
					(size 1.016 1.016)
					(thickness 0.1524)
				)
				(justify mirror)
			)
		)
		(duplicate_pad_numbers_are_jumpers no)
		(fp_line
			(start 0.2032 0)
			(end 0.4191 0)
			(stroke
				(width 0.2032)
				(type default)
			)
			(layer "B.SilkS")
		)
		(fp_line
			(start -0.4318 0)
			(end -0.2032 0)
			(stroke
				(width 0.2032)
				(type default)
			)
			(layer "B.SilkS")
		)
		(fp_rect
			(start 0.635 1.1811)
			(end -0.635 -1.1811)
			(stroke
				(width 0)
				(type default)
			)
			(fill no)
			(layer "B.CrtYd")
		)
		(fp_rect
			(start 0.635 1.1811)
			(end -0.635 -1.1811)
			(stroke
				(width 0)
				(type default)
			)
			(fill no)
			(layer "B.Fab")
		)
		(pad "1" smd custom
			(at 0 -0.6604)
			(size 0.19685 0.19685)
			(layers "B.Cu" "B.Mask" "B.Paste")
			(net "P3V3")
			(options
				(clearance outline)
				(anchor circle)
			)
			(primitives
				(gr_poly
					(pts
						(arc
							(start 0.508 0.2921)
							(mid 0.478242 0.363942)
							(end 0.4064 0.3937)
						)
						(arc
							(start -0.4064 0.3937)
							(mid -0.478242 0.363942)
							(end -0.508 0.2921)
						)
						(arc
							(start -0.508 -0.2921)
							(mid -0.478242 -0.363942)
							(end -0.4064 -0.3937)
						)
						(arc
							(start 0.4064 -0.3937)
							(mid 0.478242 -0.363942)
							(end 0.508 -0.2921)
						)
					)
					(width 0)
					(fill yes)
				)
			)
		)
		(pad "2" smd custom
			(at 0 0.6604)
			(size 0.19685 0.19685)
			(layers "B.Cu" "B.Mask" "B.Paste")
			(net "P3V3_DISCHARGE_D")
			(options
				(clearance outline)
				(anchor circle)
			)
			(primitives
				(gr_poly
					(pts
						(arc
							(start 0.508 0.2921)
							(mid 0.478242 0.363942)
							(end 0.4064 0.3937)
						)
						(arc
							(start -0.4064 0.3937)
							(mid -0.478242 0.363942)
							(end -0.508 0.2921)
						)
						(arc
							(start -0.508 -0.2921)
							(mid -0.478242 -0.363942)
							(end -0.4064 -0.3937)
						)
						(arc
							(start 0.4064 -0.3937)
							(mid 0.478242 -0.363942)
							(end 0.508 -0.2921)
						)
					)
					(width 0)
					(fill yes)
				)
			)
		)
	)
	(footprint ""
		(layer "B.Cu")
		(at 178.054 -42.545)
		(property "Reference" "R175"
			(at 0 0 0)
			(layer "B.SilkS")
			(hide yes)
			(effects
				(font
					(size 1.27 1.27)
				)
				(justify mirror)
			)
		)
		(property "Value" "0R2J-2-GP"
			(at -1.7907 -1.1176 0)
			(unlocked yes)
			(layer "B.Fab")
			(hide yes)
			(effects
				(font
					(size 1.016 1.016)
					(thickness 0.1524)
				)
				(justify mirror)
			)
		)
		(property "Device Type" "R402H16"
			(at -1.7907 -2.6416 0)
			(unlocked yes)
			(layer "B.Fab")
			(hide yes)
			(effects
				(font
					(size 1.016 1.016)
					(thickness 0.1524)
				)
				(justify mirror)
			)
		)
		(duplicate_pad_numbers_are_jumpers no)
		(fp_rect
			(start 0.381 0.8382)
			(end -0.381 -0.8382)
			(stroke
				(width 0)
				(type default)
			)
			(fill no)
			(layer "B.CrtYd")
		)
		(fp_rect
			(start 0.381 0.8382)
			(end -0.381 -0.8382)
			(stroke
				(width 0)
				(type default)
			)
			(fill no)
			(layer "B.Fab")
		)
		(pad "1" smd custom
			(at 0 -0.4318 180)
			(size 0.127 0.127)
			(layers "B.Cu" "B.Mask" "B.Paste")
			(net "SPI_SW_RST#")
			(options
				(clearance outline)
				(anchor circle)
			)
			(primitives
				(gr_poly
					(pts
						(arc
							(start -0.2032 0.2794)
							(mid -0.239121 0.264521)
							(end -0.254 0.2286)
						)
						(arc
							(start -0.254 -0.2286)
							(mid -0.239121 -0.264521)
							(end -0.2032 -0.2794)
						)
						(arc
							(start 0.2032 -0.2794)
							(mid 0.239121 -0.264521)
							(end 0.254 -0.2286)
						)
						(arc
							(start 0.254 0.2286)
							(mid 0.239121 0.264521)
							(end 0.2032 0.2794)
						)
					)
					(width 0)
					(fill yes)
				)
			)
		)
		(pad "2" smd custom
			(at 0 0.4318 180)
			(size 0.127 0.127)
			(layers "B.Cu" "B.Mask" "B.Paste")
			(net "CPU_RSMRST#")
			(options
				(clearance outline)
				(anchor circle)
			)
			(primitives
				(gr_poly
					(pts
						(arc
							(start -0.2032 0.2794)
							(mid -0.239121 0.264521)
							(end -0.254 0.2286)
						)
						(arc
							(start -0.254 -0.2286)
							(mid -0.239121 -0.264521)
							(end -0.2032 -0.2794)
						)
						(arc
							(start 0.2032 -0.2794)
							(mid 0.239121 -0.264521)
							(end 0.254 -0.2286)
						)
						(arc
							(start 0.254 0.2286)
							(mid 0.239121 0.264521)
							(end 0.2032 0.2794)
						)
					)
					(width 0)
					(fill yes)
				)
			)
		)
	)
	(footprint ""
		(layer "B.Cu")
		(at 193.548 -37.338 180)
		(property "Reference" "PR167"
			(at 0 0 0)
			(layer "B.SilkS")
			(hide yes)
			(effects
				(font
					(size 1.27 1.27)
				)
				(justify mirror)
			)
		)
		(property "Value" "3K3R3F-GP"
			(at 0.0254 -2.0193 180)
			(unlocked yes)
			(layer "B.Fab")
			(hide yes)
			(effects
				(font
					(size 1.016 1.016)
					(thickness 0.1524)
				)
				(justify mirror)
			)
		)
		(property "Device Type" "R603H22"
			(at 0.0254 -3.5433 180)
			(unlocked yes)
			(layer "B.Fab")
			(hide yes)
			(effects
				(font
					(size 1.016 1.016)
					(thickness 0.1524)
				)
				(justify mirror)
			)
		)
		(duplicate_pad_numbers_are_jumpers no)
		(fp_line
			(start 0.2032 0)
			(end 0.4191 0)
			(stroke
				(width 0.2032)
				(type default)
			)
			(layer "B.SilkS")
		)
		(fp_line
			(start -0.4318 0)
			(end -0.2032 0)
			(stroke
				(width 0.2032)
				(type default)
			)
			(layer "B.SilkS")
		)
		(fp_rect
			(start 0.635 1.1811)
			(end -0.635 -1.1811)
			(stroke
				(width 0)
				(type default)
			)
			(fill no)
			(layer "B.CrtYd")
		)
		(fp_rect
			(start 0.635 1.1811)
			(end -0.635 -1.1811)
			(stroke
				(width 0)
				(type default)
			)
			(fill no)
			(layer "B.Fab")
		)
		(pad "1" smd custom
			(at 0 -0.6604)
			(size 0.19685 0.19685)
			(layers "B.Cu" "B.Mask" "B.Paste")
			(net "P12V")
			(options
				(clearance outline)
				(anchor circle)
			)
			(primitives
				(gr_poly
					(pts
						(arc
							(start 0.508 0.2921)
							(mid 0.478242 0.363942)
							(end 0.4064 0.3937)
						)
						(arc
							(start -0.4064 0.3937)
							(mid -0.478242 0.363942)
							(end -0.508 0.2921)
						)
						(arc
							(start -0.508 -0.2921)
							(mid -0.478242 -0.363942)
							(end -0.4064 -0.3937)
						)
						(arc
							(start 0.4064 -0.3937)
							(mid 0.478242 -0.363942)
							(end 0.508 -0.2921)
						)
					)
					(width 0)
					(fill yes)
				)
			)
		)
		(pad "2" smd custom
			(at 0 0.6604)
			(size 0.19685 0.19685)
			(layers "B.Cu" "B.Mask" "B.Paste")
			(net "VDDR_Z")
			(options
				(clearance outline)
				(anchor circle)
			)
			(primitives
				(gr_poly
					(pts
						(arc
							(start 0.508 0.2921)
							(mid 0.478242 0.363942)
							(end 0.4064 0.3937)
						)
						(arc
							(start -0.4064 0.3937)
							(mid -0.478242 0.363942)
							(end -0.508 0.2921)
						)
						(arc
							(start -0.508 -0.2921)
							(mid -0.478242 -0.363942)
							(end -0.4064 -0.3937)
						)
						(arc
							(start 0.4064 -0.3937)
							(mid 0.478242 -0.363942)
							(end 0.508 -0.2921)
						)
					)
					(width 0)
					(fill yes)
				)
			)
		)
	)
)
